(kicad_pcb
	(version 20260206)
	(generator "pcbnew")
	(generator_version "10.0")
	(general
		(thickness 1.6)
		(legacy_teardrops no)
	)
	(paper "A4")
	(title_block
		(title "03242023_DA0F0TMBIJ0_F0T_Motherboard_J_brd_V01_OCP.brd")
		(comment 1 "Grand Teton / footprints 3575-3580 of 6105")
	)
	(layers
		(0 "F.Cu" signal "TOP")
		(4 "In1.Cu" signal "GND")
		(6 "In2.Cu" signal "IN1")
		(8 "In3.Cu" signal "GND1")
		(10 "In4.Cu" signal "IN2")
		(12 "In5.Cu" signal "GND2")
		(14 "In6.Cu" signal "IN3")
		(16 "In7.Cu" signal "GND3")
		(18 "In8.Cu" signal "VCC")
		(20 "In9.Cu" signal "VCC1")
		(22 "In10.Cu" signal "GND4")
		(24 "In11.Cu" signal "IN4")
		(26 "In12.Cu" signal "GND5")
		(28 "In13.Cu" signal "IN5")
		(30 "In14.Cu" signal "GND6")
		(32 "In15.Cu" signal "IN6")
		(34 "In16.Cu" signal "GND7")
		(2 "B.Cu" signal "BOTTOM")
		(9 "F.Adhes" user "F.Adhesive")
		(11 "B.Adhes" user "B.Adhesive")
		(13 "F.Paste" user "Package Geometry/Pastemask Top")
		(15 "B.Paste" user "Package Geometry/Pastemask Bottom")
		(5 "F.SilkS" user "Ref Des/Silkscreen Top")
		(7 "B.SilkS" user "Ref Des/Silkscreen Bottom")
		(1 "F.Mask" user "Board Geometry/Soldermask Top")
		(3 "B.Mask" user "Board Geometry/Soldermask Bottom")
		(17 "Dwgs.User" user "User.Drawings")
		(19 "Cmts.User" user "User.Comments")
		(21 "Eco1.User" user "User.Eco1")
		(23 "Eco2.User" user "User.Eco2")
		(25 "Edge.Cuts" user "Board Geometry/Outline")
		(27 "Margin" user)
		(31 "F.CrtYd" user "Package Geometry/Place Bound Top")
		(29 "B.CrtYd" user "Package Geometry/Place Bound Bottom")
		(35 "F.Fab" user "Ref Des/Assembly Top")
		(33 "B.Fab" user "Ref Des/Assembly Bottom")
	)
	(footprint ""
		(layer "F.Cu")
		(at 427.097952 -124.91466 180)
		(property "Reference" "PR634"
			(at 0 0 180)
			(layer "F.SilkS")
			(hide yes)
			(effects
				(font
					(size 1.27 1.27)
				)
			)
		)
		(property "Value" ""
			(at 0 0 180)
			(layer "F.Fab")
			(effects
				(font
					(size 1.27 1.27)
				)
			)
		)
		(duplicate_pad_numbers_are_jumpers no)
		(fp_line
			(start 0.7874 0.4064)
			(end -0.7874 0.4064)
			(stroke
				(width 0.1524)
				(type default)
			)
			(layer "F.SilkS")
		)
		(fp_line
			(start 0.7874 -0.4064)
			(end 0.7874 0.4064)
			(stroke
				(width 0.1524)
				(type default)
			)
			(layer "F.SilkS")
		)
		(fp_line
			(start -0.7874 0.4064)
			(end -0.7874 -0.4064)
			(stroke
				(width 0.1524)
				(type default)
			)
			(layer "F.SilkS")
		)
		(fp_line
			(start -0.7874 -0.4064)
			(end 0.7874 -0.4064)
			(stroke
				(width 0.1524)
				(type default)
			)
			(layer "F.SilkS")
		)
		(fp_line
			(start 0.67945 0.3048)
			(end 0.120396 0.3048)
			(stroke
				(width 0.1)
				(type default)
			)
			(layer "F.Fab")
		)
		(fp_line
			(start 0.67945 -0.3048)
			(end 0.67945 0.3048)
			(stroke
				(width 0.1)
				(type default)
			)
			(layer "F.Fab")
		)
		(fp_line
			(start 0.12065 -0.2794)
			(end 0.12065 -0.3048)
			(stroke
				(width 0.1)
				(type default)
			)
			(layer "F.Fab")
		)
		(fp_line
			(start 0.12065 -0.3048)
			(end 0.67945 -0.3048)
			(stroke
				(width 0.1)
				(type default)
			)
			(layer "F.Fab")
		)
		(fp_line
			(start 0.120396 0.3048)
			(end 0.120396 0.2794)
			(stroke
				(width 0.1)
				(type default)
			)
			(layer "F.Fab")
		)
		(fp_line
			(start 0.120396 0.2794)
			(end -0.12065 0.2794)
			(stroke
				(width 0.1)
				(type default)
			)
			(layer "F.Fab")
		)
		(fp_line
			(start -0.12065 0.3048)
			(end -0.67945 0.3048)
			(stroke
				(width 0.1)
				(type default)
			)
			(layer "F.Fab")
		)
		(fp_line
			(start -0.12065 0.2794)
			(end -0.12065 0.3048)
			(stroke
				(width 0.1)
				(type default)
			)
			(layer "F.Fab")
		)
		(fp_line
			(start -0.12065 -0.2794)
			(end 0.12065 -0.2794)
			(stroke
				(width 0.1)
				(type default)
			)
			(layer "F.Fab")
		)
		(fp_line
			(start -0.12065 -0.305054)
			(end -0.12065 -0.2794)
			(stroke
				(width 0.1)
				(type default)
			)
			(layer "F.Fab")
		)
		(fp_line
			(start -0.67945 0.3048)
			(end -0.67945 -0.305054)
			(stroke
				(width 0.1)
				(type default)
			)
			(layer "F.Fab")
		)
		(fp_line
			(start -0.67945 -0.305054)
			(end -0.12065 -0.305054)
			(stroke
				(width 0.1)
				(type default)
			)
			(layer "F.Fab")
		)
		(pad "1" smd circle
			(at -0.40005 0 180)
			(size 0 0)
			(layers "F.Cu" "F.Mask" "F.Paste")
			(net "PVCCD_HV_CPU0_ATSEN")
		)
		(pad "2" smd circle
			(at 0.40005 0 180)
			(size 0 0)
			(layers "F.Cu" "F.Mask" "F.Paste")
			(net "GND")
		)
	)
	(footprint ""
		(layer "F.Cu")
		(at 366.95888 -357.114348 90)
		(property "Reference" "PR2336"
			(at 0 0 90)
			(layer "F.SilkS")
			(hide yes)
			(effects
				(font
					(size 1.27 1.27)
				)
			)
		)
		(property "Value" ""
			(at 0 0 90)
			(layer "F.Fab")
			(effects
				(font
					(size 1.27 1.27)
				)
			)
		)
		(duplicate_pad_numbers_are_jumpers no)
		(fp_line
			(start 0.7874 -0.4064)
			(end 0.7874 0.4064)
			(stroke
				(width 0.1524)
				(type default)
			)
			(layer "F.SilkS")
		)
		(fp_line
			(start -0.7874 -0.4064)
			(end 0.7874 -0.4064)
			(stroke
				(width 0.1524)
				(type default)
			)
			(layer "F.SilkS")
		)
		(fp_line
			(start 0.7874 0.4064)
			(end -0.7874 0.4064)
			(stroke
				(width 0.1524)
				(type default)
			)
			(layer "F.SilkS")
		)
		(fp_line
			(start -0.7874 0.4064)
			(end -0.7874 -0.4064)
			(stroke
				(width 0.1524)
				(type default)
			)
			(layer "F.SilkS")
		)
		(fp_line
			(start -0.12065 -0.305054)
			(end -0.12065 -0.2794)
			(stroke
				(width 0.1)
				(type default)
			)
			(layer "F.Fab")
		)
		(fp_line
			(start -0.67945 -0.305054)
			(end -0.12065 -0.305054)
			(stroke
				(width 0.1)
				(type default)
			)
			(layer "F.Fab")
		)
		(fp_line
			(start 0.67945 -0.3048)
			(end 0.67945 0.3048)
			(stroke
				(width 0.1)
				(type default)
			)
			(layer "F.Fab")
		)
		(fp_line
			(start 0.12065 -0.3048)
			(end 0.67945 -0.3048)
			(stroke
				(width 0.1)
				(type default)
			)
			(layer "F.Fab")
		)
		(fp_line
			(start 0.12065 -0.2794)
			(end 0.12065 -0.3048)
			(stroke
				(width 0.1)
				(type default)
			)
			(layer "F.Fab")
		)
		(fp_line
			(start -0.12065 -0.2794)
			(end 0.12065 -0.2794)
			(stroke
				(width 0.1)
				(type default)
			)
			(layer "F.Fab")
		)
		(fp_line
			(start 0.120396 0.2794)
			(end -0.12065 0.2794)
			(stroke
				(width 0.1)
				(type default)
			)
			(layer "F.Fab")
		)
		(fp_line
			(start -0.12065 0.2794)
			(end -0.12065 0.3048)
			(stroke
				(width 0.1)
				(type default)
			)
			(layer "F.Fab")
		)
		(fp_line
			(start 0.67945 0.3048)
			(end 0.120396 0.3048)
			(stroke
				(width 0.1)
				(type default)
			)
			(layer "F.Fab")
		)
		(fp_line
			(start 0.120396 0.3048)
			(end 0.120396 0.2794)
			(stroke
				(width 0.1)
				(type default)
			)
			(layer "F.Fab")
		)
		(fp_line
			(start -0.12065 0.3048)
			(end -0.67945 0.3048)
			(stroke
				(width 0.1)
				(type default)
			)
			(layer "F.Fab")
		)
		(fp_line
			(start -0.67945 0.3048)
			(end -0.67945 -0.305054)
			(stroke
				(width 0.1)
				(type default)
			)
			(layer "F.Fab")
		)
		(pad "1" smd circle
			(at -0.40005 0 90)
			(size 0 0)
			(layers "F.Cu" "F.Mask" "F.Paste")
			(net "PVPP_HBM_CPU0_FB")
		)
		(pad "2" smd circle
			(at 0.40005 0 90)
			(size 0 0)
			(layers "F.Cu" "F.Mask" "F.Paste")
			(net "FM_HBM_VPP_SEL_CPU0_D")
		)
	)
	(footprint ""
		(layer "F.Cu")
		(at 298.342304 -426.478446 -90)
		(property "Reference" "R4138"
			(at 0 0 270)
			(layer "F.SilkS")
			(hide yes)
			(effects
				(font
					(size 1.27 1.27)
				)
			)
		)
		(property "Value" ""
			(at 0 0 270)
			(layer "F.Fab")
			(effects
				(font
					(size 1.27 1.27)
				)
			)
		)
		(duplicate_pad_numbers_are_jumpers no)
		(fp_line
			(start -0.7874 0.4064)
			(end -0.7874 -0.4064)
			(stroke
				(width 0.1524)
				(type default)
			)
			(layer "F.SilkS")
		)
		(fp_line
			(start 0.7874 0.4064)
			(end -0.7874 0.4064)
			(stroke
				(width 0.1524)
				(type default)
			)
			(layer "F.SilkS")
		)
		(fp_line
			(start -0.7874 -0.4064)
			(end 0.7874 -0.4064)
			(stroke
				(width 0.1524)
				(type default)
			)
			(layer "F.SilkS")
		)
		(fp_line
			(start 0.7874 -0.4064)
			(end 0.7874 0.4064)
			(stroke
				(width 0.1524)
				(type default)
			)
			(layer "F.SilkS")
		)
		(fp_line
			(start -0.67945 0.3048)
			(end -0.67945 -0.305054)
			(stroke
				(width 0.1)
				(type default)
			)
			(layer "F.Fab")
		)
		(fp_line
			(start -0.12065 0.3048)
			(end -0.67945 0.3048)
			(stroke
				(width 0.1)
				(type default)
			)
			(layer "F.Fab")
		)
		(fp_line
			(start 0.120396 0.3048)
			(end 0.120396 0.2794)
			(stroke
				(width 0.1)
				(type default)
			)
			(layer "F.Fab")
		)
		(fp_line
			(start 0.67945 0.3048)
			(end 0.120396 0.3048)
			(stroke
				(width 0.1)
				(type default)
			)
			(layer "F.Fab")
		)
		(fp_line
			(start -0.12065 0.2794)
			(end -0.12065 0.3048)
			(stroke
				(width 0.1)
				(type default)
			)
			(layer "F.Fab")
		)
		(fp_line
			(start 0.120396 0.2794)
			(end -0.12065 0.2794)
			(stroke
				(width 0.1)
				(type default)
			)
			(layer "F.Fab")
		)
		(fp_line
			(start -0.12065 -0.2794)
			(end 0.12065 -0.2794)
			(stroke
				(width 0.1)
				(type default)
			)
			(layer "F.Fab")
		)
		(fp_line
			(start 0.12065 -0.2794)
			(end 0.12065 -0.3048)
			(stroke
				(width 0.1)
				(type default)
			)
			(layer "F.Fab")
		)
		(fp_line
			(start 0.12065 -0.3048)
			(end 0.67945 -0.3048)
			(stroke
				(width 0.1)
				(type default)
			)
			(layer "F.Fab")
		)
		(fp_line
			(start 0.67945 -0.3048)
			(end 0.67945 0.3048)
			(stroke
				(width 0.1)
				(type default)
			)
			(layer "F.Fab")
		)
		(fp_line
			(start -0.67945 -0.305054)
			(end -0.12065 -0.305054)
			(stroke
				(width 0.1)
				(type default)
			)
			(layer "F.Fab")
		)
		(fp_line
			(start -0.12065 -0.305054)
			(end -0.12065 -0.2794)
			(stroke
				(width 0.1)
				(type default)
			)
			(layer "F.Fab")
		)
		(pad "1" smd circle
			(at -0.40005 0 270)
			(size 0 0)
			(layers "F.Cu" "F.Mask" "F.Paste")
			(net "P3V3_AUX")
		)
		(pad "2" smd circle
			(at 0.40005 0 270)
			(size 0 0)
			(layers "F.Cu" "F.Mask" "F.Paste")
			(net "GPU_3V3IO_RSVD5_FFU_N")
		)
	)
	(footprint ""
		(layer "F.Cu")
		(at 300.84395 -417.2204)
		(property "Reference" "R4573"
			(at 0 0 0)
			(layer "F.SilkS")
			(hide yes)
			(effects
				(font
					(size 1.27 1.27)
				)
			)
		)
		(property "Value" ""
			(at 0 0 0)
			(layer "F.Fab")
			(effects
				(font
					(size 1.27 1.27)
				)
			)
		)
		(duplicate_pad_numbers_are_jumpers no)
		(fp_line
			(start -0.7874 -0.4064)
			(end 0.7874 -0.4064)
			(stroke
				(width 0.1524)
				(type default)
			)
			(layer "F.SilkS")
		)
		(fp_line
			(start -0.7874 0.4064)
			(end -0.7874 -0.4064)
			(stroke
				(width 0.1524)
				(type default)
			)
			(layer "F.SilkS")
		)
		(fp_line
			(start 0.7874 -0.4064)
			(end 0.7874 0.4064)
			(stroke
				(width 0.1524)
				(type default)
			)
			(layer "F.SilkS")
		)
		(fp_line
			(start 0.7874 0.4064)
			(end -0.7874 0.4064)
			(stroke
				(width 0.1524)
				(type default)
			)
			(layer "F.SilkS")
		)
		(fp_line
			(start -0.67945 -0.305054)
			(end -0.12065 -0.305054)
			(stroke
				(width 0.1)
				(type default)
			)
			(layer "F.Fab")
		)
		(fp_line
			(start -0.67945 0.3048)
			(end -0.67945 -0.305054)
			(stroke
				(width 0.1)
				(type default)
			)
			(layer "F.Fab")
		)
		(fp_line
			(start -0.12065 -0.305054)
			(end -0.12065 -0.2794)
			(stroke
				(width 0.1)
				(type default)
			)
			(layer "F.Fab")
		)
		(fp_line
			(start -0.12065 -0.2794)
			(end 0.12065 -0.2794)
			(stroke
				(width 0.1)
				(type default)
			)
			(layer "F.Fab")
		)
		(fp_line
			(start -0.12065 0.2794)
			(end -0.12065 0.3048)
			(stroke
				(width 0.1)
				(type default)
			)
			(layer "F.Fab")
		)
		(fp_line
			(start -0.12065 0.3048)
			(end -0.67945 0.3048)
			(stroke
				(width 0.1)
				(type default)
			)
			(layer "F.Fab")
		)
		(fp_line
			(start 0.120396 0.2794)
			(end -0.12065 0.2794)
			(stroke
				(width 0.1)
				(type default)
			)
			(layer "F.Fab")
		)
		(fp_line
			(start 0.120396 0.3048)
			(end 0.120396 0.2794)
			(stroke
				(width 0.1)
				(type default)
			)
			(layer "F.Fab")
		)
		(fp_line
			(start 0.12065 -0.3048)
			(end 0.67945 -0.3048)
			(stroke
				(width 0.1)
				(type default)
			)
			(layer "F.Fab")
		)
		(fp_line
			(start 0.12065 -0.2794)
			(end 0.12065 -0.3048)
			(stroke
				(width 0.1)
				(type default)
			)
			(layer "F.Fab")
		)
		(fp_line
			(start 0.67945 -0.3048)
			(end 0.67945 0.3048)
			(stroke
				(width 0.1)
				(type default)
			)
			(layer "F.Fab")
		)
		(fp_line
			(start 0.67945 0.3048)
			(end 0.120396 0.3048)
			(stroke
				(width 0.1)
				(type default)
			)
			(layer "F.Fab")
		)
		(pad "1" smd circle
			(at -0.40005 0)
			(size 0 0)
			(layers "F.Cu" "F.Mask" "F.Paste")
			(net "PRSNT_CABLE_GPU_B3_N")
		)
		(pad "2" smd circle
			(at 0.40005 0)
			(size 0 0)
			(layers "F.Cu" "F.Mask" "F.Paste")
			(net "PRSNT_CABLE_GPU_B3_ISO_N")
		)
	)
	(footprint ""
		(layer "F.Cu")
		(at 131.425696 -341.729822 -90)
		(property "Reference" "PC510"
			(at 0 0 270)
			(layer "F.SilkS")
			(hide yes)
			(effects
				(font
					(size 1.27 1.27)
				)
			)
		)
		(property "Value" ""
			(at 0 0 270)
			(layer "F.Fab")
			(effects
				(font
					(size 1.27 1.27)
				)
			)
		)
		(duplicate_pad_numbers_are_jumpers no)
		(fp_line
			(start -0.7874 0.4064)
			(end -0.7874 -0.4064)
			(stroke
				(width 0.1524)
				(type default)
			)
			(layer "F.SilkS")
		)
		(fp_line
			(start 0.7874 0.4064)
			(end -0.7874 0.4064)
			(stroke
				(width 0.1524)
				(type default)
			)
			(layer "F.SilkS")
		)
		(fp_line
			(start -0.7874 -0.4064)
			(end 0.7874 -0.4064)
			(stroke
				(width 0.1524)
				(type default)
			)
			(layer "F.SilkS")
		)
		(fp_line
			(start 0.7874 -0.4064)
			(end 0.7874 0.4064)
			(stroke
				(width 0.1524)
				(type default)
			)
			(layer "F.SilkS")
		)
		(fp_line
			(start -0.67945 0.3048)
			(end -0.67945 -0.305054)
			(stroke
				(width 0.1)
				(type default)
			)
			(layer "F.Fab")
		)
		(fp_line
			(start -0.12065 0.3048)
			(end -0.67945 0.3048)
			(stroke
				(width 0.1)
				(type default)
			)
			(layer "F.Fab")
		)
		(fp_line
			(start 0.120396 0.3048)
			(end 0.120396 0.2794)
			(stroke
				(width 0.1)
				(type default)
			)
			(layer "F.Fab")
		)
		(fp_line
			(start 0.67945 0.3048)
			(end 0.120396 0.3048)
			(stroke
				(width 0.1)
				(type default)
			)
			(layer "F.Fab")
		)
		(fp_line
			(start -0.12065 0.2794)
			(end -0.12065 0.3048)
			(stroke
				(width 0.1)
				(type default)
			)
			(layer "F.Fab")
		)
		(fp_line
			(start 0.120396 0.2794)
			(end -0.12065 0.2794)
			(stroke
				(width 0.1)
				(type default)
			)
			(layer "F.Fab")
		)
		(fp_line
			(start -0.12065 -0.2794)
			(end 0.12065 -0.2794)
			(stroke
				(width 0.1)
				(type default)
			)
			(layer "F.Fab")
		)
		(fp_line
			(start 0.12065 -0.2794)
			(end 0.12065 -0.3048)
			(stroke
				(width 0.1)
				(type default)
			)
			(layer "F.Fab")
		)
		(fp_line
			(start 0.12065 -0.3048)
			(end 0.67945 -0.3048)
			(stroke
				(width 0.1)
				(type default)
			)
			(layer "F.Fab")
		)
		(fp_line
			(start 0.67945 -0.3048)
			(end 0.67945 0.3048)
			(stroke
				(width 0.1)
				(type default)
			)
			(layer "F.Fab")
		)
		(fp_line
			(start -0.67945 -0.305054)
			(end -0.12065 -0.305054)
			(stroke
				(width 0.1)
				(type default)
			)
			(layer "F.Fab")
		)
		(fp_line
			(start -0.12065 -0.305054)
			(end -0.12065 -0.2794)
			(stroke
				(width 0.1)
				(type default)
			)
			(layer "F.Fab")
		)
		(pad "1" smd circle
			(at -0.40005 0 270)
			(size 0 0)
			(layers "F.Cu" "F.Mask" "F.Paste")
			(net "SW_PVCCIN_CPU1_BOOT5_R")
		)
		(pad "2" smd circle
			(at 0.40005 0 270)
			(size 0 0)
			(layers "F.Cu" "F.Mask" "F.Paste")
			(net "SW_PVCCIN_CPU1_BOOTR5")
		)
	)
	(footprint ""
		(layer "F.Cu")
		(at 168.11371 -129.553716 90)
		(property "Reference" "R1640"
			(at 0 0 90)
			(layer "F.SilkS")
			(hide yes)
			(effects
				(font
					(size 1.27 1.27)
				)
			)
		)
		(property "Value" ""
			(at 0 0 90)
			(layer "F.Fab")
			(effects
				(font
					(size 1.27 1.27)
				)
			)
		)
		(duplicate_pad_numbers_are_jumpers no)
		(fp_line
			(start 0.7874 -0.4064)
			(end 0.7874 0.4064)
			(stroke
				(width 0.1524)
				(type default)
			)
			(layer "F.SilkS")
		)
		(fp_line
			(start -0.7874 -0.4064)
			(end 0.7874 -0.4064)
			(stroke
				(width 0.1524)
				(type default)
			)
			(layer "F.SilkS")
		)
		(fp_line
			(start 0.7874 0.4064)
			(end -0.7874 0.4064)
			(stroke
				(width 0.1524)
				(type default)
			)
			(layer "F.SilkS")
		)
		(fp_line
			(start -0.7874 0.4064)
			(end -0.7874 -0.4064)
			(stroke
				(width 0.1524)
				(type default)
			)
			(layer "F.SilkS")
		)
		(fp_line
			(start -0.12065 -0.305054)
			(end -0.12065 -0.2794)
			(stroke
				(width 0.1)
				(type default)
			)
			(layer "F.Fab")
		)
		(fp_line
			(start -0.67945 -0.305054)
			(end -0.12065 -0.305054)
			(stroke
				(width 0.1)
				(type default)
			)
			(layer "F.Fab")
		)
		(fp_line
			(start 0.67945 -0.3048)
			(end 0.67945 0.3048)
			(stroke
				(width 0.1)
				(type default)
			)
			(layer "F.Fab")
		)
		(fp_line
			(start 0.12065 -0.3048)
			(end 0.67945 -0.3048)
			(stroke
				(width 0.1)
				(type default)
			)
			(layer "F.Fab")
		)
		(fp_line
			(start 0.12065 -0.2794)
			(end 0.12065 -0.3048)
			(stroke
				(width 0.1)
				(type default)
			)
			(layer "F.Fab")
		)
		(fp_line
			(start -0.12065 -0.2794)
			(end 0.12065 -0.2794)
			(stroke
				(width 0.1)
				(type default)
			)
			(layer "F.Fab")
		)
		(fp_line
			(start 0.120396 0.2794)
			(end -0.12065 0.2794)
			(stroke
				(width 0.1)
				(type default)
			)
			(layer "F.Fab")
		)
		(fp_line
			(start -0.12065 0.2794)
			(end -0.12065 0.3048)
			(stroke
				(width 0.1)
				(type default)
			)
			(layer "F.Fab")
		)
		(fp_line
			(start 0.67945 0.3048)
			(end 0.120396 0.3048)
			(stroke
				(width 0.1)
				(type default)
			)
			(layer "F.Fab")
		)
		(fp_line
			(start 0.120396 0.3048)
			(end 0.120396 0.2794)
			(stroke
				(width 0.1)
				(type default)
			)
			(layer "F.Fab")
		)
		(fp_line
			(start -0.12065 0.3048)
			(end -0.67945 0.3048)
			(stroke
				(width 0.1)
				(type default)
			)
			(layer "F.Fab")
		)
		(fp_line
			(start -0.67945 0.3048)
			(end -0.67945 -0.305054)
			(stroke
				(width 0.1)
				(type default)
			)
			(layer "F.Fab")
		)
		(pad "1" smd circle
			(at -0.40005 0 90)
			(size 0 0)
			(layers "F.Cu" "F.Mask" "F.Paste")
			(net "FM_P5V_EN")
		)
		(pad "2" smd circle
			(at 0.40005 0 90)
			(size 0 0)
			(layers "F.Cu" "F.Mask" "F.Paste")
			(net "VR_P5V_EN")
		)
	)
)
